(kicad_pcb
	(version 20241229)
	(generator "pcbnew")
	(generator_version "9.0")
	(general
		(thickness 1.6)
		(legacy_teardrops no)
	)
	(paper "A4")
	(title_block
		(title "GMSL Deserializer")
		(date "2025-10-09")
		(rev "1.0.4")
		(company "Antmicro Ltd")
		(comment 1 "www.antmicro.com")
		(comment 9 "footprints 171-174 of 235")
	)
	(layers
		(0 "F.Cu" signal)
		(4 "In1.Cu" power)
		(6 "In2.Cu" power)
		(2 "B.Cu" signal)
		(9 "F.Adhes" user "F.Adhesive")
		(11 "B.Adhes" user "B.Adhesive")
		(13 "F.Paste" user)
		(15 "B.Paste" user)
		(5 "F.SilkS" user "F.Silkscreen")
		(7 "B.SilkS" user "B.Silkscreen")
		(1 "F.Mask" user)
		(3 "B.Mask" user)
		(17 "Dwgs.User" user "User.Drawings")
		(19 "Cmts.User" user "User.Comments")
		(21 "Eco1.User" user "User.Eco1")
		(23 "Eco2.User" user "User.Eco2")
		(25 "Edge.Cuts" user)
		(27 "Margin" user)
		(31 "F.CrtYd" user "F.Courtyard")
		(29 "B.CrtYd" user "B.Courtyard")
		(35 "F.Fab" user)
		(33 "B.Fab" user)
	)
	(footprint "antmicro-footprints:SOT-363"
		(layer "F.Cu")
		(at 178.308 56.642)
		(property "Reference" "Q3"
			(at 1.321273 0.068518 0)
			(layer "F.SilkS")
			(effects
				(font
					(size 0.7 0.7)
					(thickness 0.15)
				)
				(justify left bottom)
			)
		)
		(property "Value" "DZDH0401DW"
			(at 0 2.2 0)
			(layer "F.Fab")
			(effects
				(font
					(size 0.7 0.7)
					(thickness 0.15)
				)
				(justify left bottom)
			)
		)
		(property "Datasheet" "https://www.mouser.com/datasheet/2/115/DIOD_S_A0011803041_1-2543705.pdf"
			(at 0 0 0)
			(layer "F.Fab")
			(hide yes)
			(effects
				(font
					(size 1.27 1.27)
					(thickness 0.15)
				)
			)
		)
		(property "Description" "OR Controller N+1 ORing Controller P-Channel 1:1 SOT-363"
			(at 0 0 0)
			(layer "F.Fab")
			(hide yes)
			(effects
				(font
					(size 1.27 1.27)
					(thickness 0.15)
				)
			)
		)
		(property "Author" "Antmicro"
			(at 0 0 0)
			(layer "F.Fab")
			(hide yes)
			(effects
				(font
					(size 1 1)
					(thickness 0.15)
				)
			)
		)
		(property "License" "Apache-2.0"
			(at 0 0 0)
			(layer "F.Fab")
			(hide yes)
			(effects
				(font
					(size 1 1)
					(thickness 0.15)
				)
			)
		)
		(property "MPN" "DZDH0401DW"
			(at 0 0 0)
			(layer "F.Fab")
			(hide yes)
			(effects
				(font
					(size 1 1)
					(thickness 0.15)
				)
			)
		)
		(property "Manufacturer" "Diodes Incorporated"
			(at 0 0 0)
			(layer "F.Fab")
			(hide yes)
			(effects
				(font
					(size 1 1)
					(thickness 0.15)
				)
			)
		)
		(sheetname "/Power/")
		(sheetfile "power.kicad_sch")
		(attr smd)
		(fp_line
			(start -0.8 1.146)
			(end -0.8 1.223)
			(stroke
				(width 0.15)
				(type solid)
			)
			(layer "F.SilkS")
		)
		(fp_line
			(start -0.8 1.223)
			(end 0.803 1.223)
			(stroke
				(width 0.15)
				(type solid)
			)
			(layer "F.SilkS")
		)
		(fp_line
			(start -0.72 -1.153)
			(end -0.72 -1.228)
			(stroke
				(width 0.15)
				(type solid)
			)
			(layer "F.SilkS")
		)
		(fp_line
			(start 0.803 -1.228)
			(end -0.72 -1.228)
			(stroke
				(width 0.15)
				(type solid)
			)
			(layer "F.SilkS")
		)
		(fp_line
			(start 0.803 -1.153)
			(end 0.803 -1.228)
			(stroke
				(width 0.15)
				(type solid)
			)
			(layer "F.SilkS")
		)
		(fp_line
			(start 0.803 1.146)
			(end 0.803 1.223)
			(stroke
				(width 0.15)
				(type solid)
			)
			(layer "F.SilkS")
		)
		(fp_circle
			(center -0.978102 -1.2)
			(end -0.928102 -1.2)
			(stroke
				(width 0.15)
				(type solid)
			)
			(fill yes)
			(layer "F.SilkS")
		)
		(fp_rect
			(start 1.3 -1.3)
			(end -1.3 1.3)
			(stroke
				(width 0.05)
				(type solid)
			)
			(fill no)
			(layer "F.CrtYd")
		)
		(fp_line
			(start -0.1 -1.1)
			(end -0.68 -0.52)
			(stroke
				(width 0.15)
				(type solid)
			)
			(layer "F.Fab")
		)
		(fp_rect
			(start 0.68 1.1)
			(end -0.68 -1.1)
			(stroke
				(width 0.15)
				(type solid)
			)
			(fill no)
			(layer "F.Fab")
		)
		(pad "1" smd custom
			(at -0.948 -0.752 270)
			(size 0.6 0.6)
			(layers "F.Cu" "F.Mask" "F.Paste")
			(net 149 "unconnected-(Q3-NC-Pad1)")
			(pinfunction "NC")
			(pintype "no_connect")
			(options
				(clearance outline)
				(anchor rect)
			)
			(primitives)
		)
		(pad "2" smd rect
			(at -0.948 -0.002 270)
			(size 0.4 0.6)
			(layers "F.Cu" "F.Mask" "F.Paste")
			(net 128 "Net-(Q3-REF)")
			(pinfunction "REF")
			(pintype "input")
		)
		(pad "3" smd custom
			(at -0.948 0.745 270)
			(size 0.6 0.6)
			(layers "F.Cu" "F.Mask" "F.Paste")
			(net 127 "Net-(Q2-G)")
			(pinfunction "BIAS")
			(pintype "output")
			(options
				(clearance outline)
				(anchor rect)
			)
			(primitives)
		)
		(pad "4" smd custom
			(at 0.951 0.745 270)
			(size 0.6 0.6)
			(layers "F.Cu" "F.Mask" "F.Paste")
			(net 4 "+12V")
			(pinfunction "S")
			(pintype "power_in")
			(options
				(clearance outline)
				(anchor rect)
			)
			(primitives)
		)
		(pad "5" smd rect
			(at 0.951 -0.002 270)
			(size 0.4 0.6)
			(layers "F.Cu" "F.Mask" "F.Paste")
			(net 148 "unconnected-(Q3-NC-Pad5)")
			(pinfunction "NC")
			(pintype "no_connect")
		)
		(pad "6" smd custom
			(at 0.951 -0.752 270)
			(size 0.6 0.6)
			(layers "F.Cu" "F.Mask" "F.Paste")
			(net 118 "/Connectors/DC_IN")
			(pinfunction "D")
			(pintype "power_in")
			(options
				(clearance outline)
				(anchor rect)
			)
			(primitives)
		)
	)
	(footprint "antmicro-footprints:SOT-23-5"
		(layer "F.Cu")
		(at 169.926 61.087 -90)
		(property "Reference" "U1"
			(at 2.413 1.778 90)
			(layer "F.SilkS")
			(effects
				(font
					(size 0.7 0.7)
					(thickness 0.15)
				)
				(justify left bottom)
			)
		)
		(property "Value" "SN74LV1T125DBVR"
			(at 0.002 2.799 90)
			(layer "F.Fab")
			(effects
				(font
					(size 0.7 0.7)
					(thickness 0.15)
				)
				(justify right bottom)
			)
		)
		(property "Datasheet" "https://www.ti.com/lit/ds/symlink/sn74lv1t125.pdf?HQS=dis-mous-null-mousermode-dsf-pf-null-wwe&ts=1627648952184&ref_url=https%253A%252F%252Fmouser.com%252F"
			(at 0 0 270)
			(layer "F.Fab")
			(hide yes)
			(effects
				(font
					(size 1.27 1.27)
					(thickness 0.15)
				)
			)
		)
		(property "Description" "Buffer, 74LV1T125, 1.6 V to 5.5 V, SOT-23-5"
			(at 0 0 270)
			(layer "F.Fab")
			(hide yes)
			(effects
				(font
					(size 1.27 1.27)
					(thickness 0.15)
				)
			)
		)
		(property "Author" "Antmicro"
			(at 108.839 231.013 0)
			(layer "F.Fab")
			(hide yes)
			(effects
				(font
					(size 1 1)
					(thickness 0.15)
				)
			)
		)
		(property "License" "Apache-2.0"
			(at 108.839 231.013 0)
			(layer "F.Fab")
			(hide yes)
			(effects
				(font
					(size 1 1)
					(thickness 0.15)
				)
			)
		)
		(property "MPN" "SN74LV1T125DBVR"
			(at 108.839 231.013 0)
			(layer "F.Fab")
			(hide yes)
			(effects
				(font
					(size 1 1)
					(thickness 0.15)
				)
			)
		)
		(property "Manufacturer" "Texas Instruments"
			(at 108.839 231.013 0)
			(layer "F.Fab")
			(hide yes)
			(effects
				(font
					(size 1 1)
					(thickness 0.15)
				)
			)
		)
		(sheetname "/Connectors/")
		(sheetfile "connectors.kicad_sch")
		(attr smd)
		(fp_line
			(start -0.85 1.6)
			(end -0.85 1.301)
			(stroke
				(width 0.15)
				(type solid)
			)
			(layer "F.SilkS")
		)
		(fp_line
			(start -0.55 1.6)
			(end -0.85 1.6)
			(stroke
				(width 0.15)
				(type solid)
			)
			(layer "F.SilkS")
		)
		(fp_line
			(start 0.8 1.599)
			(end 0.549 1.599)
			(stroke
				(width 0.15)
				(type solid)
			)
			(layer "F.SilkS")
		)
		(fp_line
			(start 0.8 1.3)
			(end 0.8 1.599)
			(stroke
				(width 0.15)
				(type solid)
			)
			(layer "F.SilkS")
		)
		(fp_line
			(start 0.8 0.55)
			(end 0.8 -0.55)
			(stroke
				(width 0.15)
				(type solid)
			)
			(layer "F.SilkS")
		)
		(fp_line
			(start 0.8 -1.3)
			(end 0.8 -1.6)
			(stroke
				(width 0.15)
				(type solid)
			)
			(layer "F.SilkS")
		)
		(fp_line
			(start -0.8 -1.6)
			(end -0.8 -1.3)
			(stroke
				(width 0.15)
				(type solid)
			)
			(layer "F.SilkS")
		)
		(fp_line
			(start -0.8 -1.6)
			(end -0.5 -1.6)
			(stroke
				(width 0.15)
				(type solid)
			)
			(layer "F.SilkS")
		)
		(fp_line
			(start 0.8 -1.6)
			(end 0.5 -1.6)
			(stroke
				(width 0.15)
				(type solid)
			)
			(layer "F.SilkS")
		)
		(fp_circle
			(center -1.25 -1.5)
			(end -1.2 -1.5)
			(stroke
				(width 0.15)
				(type solid)
			)
			(fill yes)
			(layer "F.SilkS")
		)
		(fp_rect
			(start 1.9 -1.76)
			(end -1.9 1.75)
			(stroke
				(width 0.05)
				(type solid)
			)
			(fill no)
			(layer "F.CrtYd")
		)
		(fp_line
			(start -0.398 -1.526)
			(end -0.874 -1.05)
			(stroke
				(width 0.15)
				(type solid)
			)
			(layer "F.Fab")
		)
		(fp_rect
			(start 0.874 1.523)
			(end -0.873 -1.525)
			(stroke
				(width 0.15)
				(type solid)
			)
			(fill no)
			(layer "F.Fab")
		)
		(pad "1" smd rect
			(at -1.351 -0.951 180)
			(size 0.55 1)
			(layers "F.Cu" "F.Mask" "F.Paste")
			(net 129 "Net-(U1-~{OE})")
			(pinfunction "~{OE}")
			(pintype "input")
		)
		(pad "2" smd rect
			(at -1.351 0 180)
			(size 0.55 1)
			(layers "F.Cu" "F.Mask" "F.Paste")
			(net 67 "/Connectors/VSYNC_CAM0")
			(pinfunction "A")
			(pintype "input")
		)
		(pad "3" smd rect
			(at -1.351 0.949 180)
			(size 0.55 1)
			(layers "F.Cu" "F.Mask" "F.Paste")
			(net 1 "GND")
			(pinfunction "GND")
			(pintype "power_in")
		)
		(pad "4" smd rect
			(at 1.35 0.949 180)
			(size 0.55 1)
			(layers "F.Cu" "F.Mask" "F.Paste")
			(net 130 "Net-(U1-Y)")
			(pinfunction "Y")
			(pintype "output")
		)
		(pad "5" smd rect
			(at 1.35 -0.951 180)
			(size 0.55 1)
			(layers "F.Cu" "F.Mask" "F.Paste")
			(net 3 "+1V8")
			(pinfunction "VCC")
			(pintype "power_in")
		)
	)
	(footprint "antmicro-footprints:R_0402_1005Metric"
		(layer "F.Cu")
		(at 144.708 73.66 -90)
		(descr "Resistor SMD 0402")
		(tags "resistor SMD 0402")
		(property "Reference" "R47"
			(at -3.0226 1.325 90)
			(layer "F.SilkS")
			(effects
				(font
					(size 0.7 0.7)
					(thickness 0.15)
				)
				(justify right bottom)
			)
		)
		(property "Value" "R_0R_0402"
			(at -1.011843 1.772047 90)
			(layer "F.Fab")
			(effects
				(font
					(size 0.7 0.7)
					(thickness 0.15)
				)
				(justify right bottom)
			)
		)
		(property "Datasheet" "https://industrial.panasonic.com/cdbs/www-data/pdf/RDA0000/AOA0000C301.pdf"
			(at 0 0 270)
			(layer "F.Fab")
			(hide yes)
			(effects
				(font
					(size 1.27 1.27)
					(thickness 0.15)
				)
			)
		)
		(property "Description" "SMD Chip Resistor, Jumper, 0 ohm, 100 mW, 0402 [1005 Metric], Thick Film, General Purpose"
			(at 0 0 270)
			(layer "F.Fab")
			(hide yes)
			(effects
				(font
					(size 1.27 1.27)
					(thickness 0.15)
				)
			)
		)
		(property "Author" "Antmicro"
			(at 71.048 218.368 0)
			(layer "F.Fab")
			(hide yes)
			(effects
				(font
					(size 1 1)
					(thickness 0.15)
				)
			)
		)
		(property "Current" "1A"
			(at 71.048 218.368 0)
			(layer "F.Fab")
			(hide yes)
			(effects
				(font
					(size 1 1)
					(thickness 0.15)
				)
			)
		)
		(property "License" "Apache-2.0"
			(at 71.048 218.368 0)
			(layer "F.Fab")
			(hide yes)
			(effects
				(font
					(size 1 1)
					(thickness 0.15)
				)
			)
		)
		(property "MPN" "ERJ2GE0R00X"
			(at 71.048 218.368 0)
			(layer "F.Fab")
			(hide yes)
			(effects
				(font
					(size 1 1)
					(thickness 0.15)
				)
			)
		)
		(property "Manufacturer" "Panasonic"
			(at 71.048 218.368 0)
			(layer "F.Fab")
			(hide yes)
			(effects
				(font
					(size 1 1)
					(thickness 0.15)
				)
			)
		)
		(property "Tolerance" ""
			(at 71.048 218.368 0)
			(layer "F.Fab")
			(hide yes)
			(effects
				(font
					(size 1 1)
					(thickness 0.15)
				)
			)
		)
		(property "Val" "0R"
			(at 71.048 218.368 0)
			(layer "F.Fab")
			(hide yes)
			(effects
				(font
					(size 1 1)
					(thickness 0.15)
				)
			)
		)
		(sheetname "/Deserializer/")
		(sheetfile "deserializer.kicad_sch")
		(attr smd)
		(fp_rect
			(start -0.925 -0.47)
			(end 0.925 0.47)
			(stroke
				(width 0.05)
				(type default)
			)
			(fill no)
			(layer "F.CrtYd")
		)
		(fp_rect
			(start -0.5 -0.25)
			(end 0.5 0.25)
			(stroke
				(width 0.15)
				(type solid)
			)
			(fill no)
			(layer "F.Fab")
		)
		(pad "1" smd roundrect
			(at -0.48 0 270)
			(size 0.59 0.64)
			(layers "F.Cu" "F.Mask" "F.Paste")
			(roundrect_rratio 0.25)
			(net 17 "/Deserializer/X2_R")
			(pintype "passive")
		)
		(pad "2" smd roundrect
			(at 0.48 0 270)
			(size 0.59 0.64)
			(layers "F.Cu" "F.Mask" "F.Paste")
			(roundrect_rratio 0.25)
			(net 75 "/Deserializer/X2")
			(pintype "passive")
		)
	)
	(footprint "antmicro-footprints:L_Coilcraft-MSS6132T"
		(layer "F.Cu")
		(at 123.19 61.976 90)
		(property "Reference" "L1"
			(at -0.635 -3.556 90)
			(layer "F.SilkS")
			(effects
				(font
					(size 0.7 0.7)
					(thickness 0.15)
				)
				(justify left bottom)
			)
		)
		(property "Value" "L_22u_1.12A_Coilcraft-MSS6132T"
			(at -0.508 4.826 90)
			(layer "F.Fab")
			(effects
				(font
					(size 0.7 0.7)
					(thickness 0.15)
				)
				(justify left bottom)
			)
		)
		(property "Datasheet" "https://www.coilcraft.com/getmedia/d035c9b3-191d-46aa-ab3f-5c1a849157c1/mss6132t.pdf"
			(at 0 0 90)
			(layer "F.Fab")
			(hide yes)
			(effects
				(font
					(size 1.27 1.27)
					(thickness 0.15)
				)
			)
		)
		(property "Description" "Power Inductor (SMT), 22 µH, 1.85 A, Shielded, 2.45 A, WE-MAPI"
			(at 0 0 90)
			(layer "F.Fab")
			(hide yes)
			(effects
				(font
					(size 1.27 1.27)
					(thickness 0.15)
				)
			)
		)
		(property "Author" "Antmicro"
			(at 185.166 -61.214 0)
			(layer "F.Fab")
			(hide yes)
			(effects
				(font
					(size 1 1)
					(thickness 0.15)
				)
			)
		)
		(property "IMax" "1.45A"
			(at 185.166 -61.214 0)
			(layer "F.Fab")
			(hide yes)
			(effects
				(font
					(size 1 1)
					(thickness 0.15)
				)
			)
		)
		(property "ISat" "1.12A"
			(at 185.166 -61.214 0)
			(layer "F.Fab")
			(hide yes)
			(effects
				(font
					(size 1 1)
					(thickness 0.15)
				)
			)
		)
		(property "License" "Apache-2.0"
			(at 185.166 -61.214 0)
			(layer "F.Fab")
			(hide yes)
			(effects
				(font
					(size 1 1)
					(thickness 0.15)
				)
			)
		)
		(property "MPN" "MSS6132T-223"
			(at 185.166 -61.214 0)
			(layer "F.Fab")
			(hide yes)
			(effects
				(font
					(size 1 1)
					(thickness 0.15)
				)
			)
		)
		(property "Manufacturer" "Coilcraft"
			(at 185.166 -61.214 0)
			(layer "F.Fab")
			(hide yes)
			(effects
				(font
					(size 1 1)
					(thickness 0.15)
				)
			)
		)
		(property "Size" "6.1x6.1"
			(at 185.166 -61.214 0)
			(layer "F.Fab")
			(hide yes)
			(effects
				(font
					(size 1 1)
					(thickness 0.15)
				)
			)
		)
		(property "Val" "22u/1.12A"
			(at 185.166 -61.214 0)
			(layer "F.Fab")
			(hide yes)
			(effects
				(font
					(size 1 1)
					(thickness 0.15)
				)
			)
		)
		(sheetname "/Power/")
		(sheetfile "power.kicad_sch")
		(attr smd)
		(fp_line
			(start -0.8 -3.05)
			(end 0.8 -3.05)
			(stroke
				(width 0.15)
				(type solid)
			)
			(layer "F.SilkS")
		)
		(fp_line
			(start -0.8 3.05)
			(end 0.8 3.05)
			(stroke
				(width 0.15)
				(type solid)
			)
			(layer "F.SilkS")
		)
		(fp_rect
			(start -3.35 -3.35)
			(end 3.35 3.35)
			(stroke
				(width 0.05)
				(type solid)
			)
			(fill no)
			(layer "F.CrtYd")
		)
		(fp_rect
			(start -3.1 -3.1)
			(end 3.1 3.1)
			(stroke
				(width 0.15)
				(type solid)
			)
			(fill no)
			(layer "F.Fab")
		)
		(pad "1" smd custom
			(at -2.71 0 180)
			(size 6 0.575)
			(layers "F.Cu" "F.Mask" "F.Paste")
			(net 4 "+12V")
			(pintype "passive")
			(options
				(clearance outline)
				(anchor rect)
			)
			(primitives
				(gr_poly
					(pts
						(xy 2.4 1.71) (xy 2.117646 1.21) (xy 1.9 0.96) (xy 1.65 0.71) (xy 1.2 0.41) (xy 0.4 0.11) (xy 0.4 0.01)
						(xy 2.9 0) (xy 2.9 1.71)
					)
					(width 0.2)
					(fill yes)
				)
				(gr_poly
					(pts
						(xy -2.4 1.731128) (xy -2.117646 1.231128) (xy -1.9 0.981128) (xy -1.65 0.731128) (xy -1.2 0.431128)
						(xy -0.4 0.131128) (xy -0.4 0.031128) (xy -2.9 0.021128) (xy -2.9 1.731128)
					)
					(width 0.2)
					(fill yes)
				)
			)
		)
		(pad "2" smd custom
			(at 2.71 0)
			(size 6 0.575)
			(layers "F.Cu" "F.Mask" "F.Paste")
			(net 51 "Net-(L1-Pad2)")
			(pintype "passive")
			(options
				(clearance outline)
				(anchor rect)
			)
			(primitives
				(gr_poly
					(pts
						(xy -2.4 1.731128) (xy -2.117646 1.231128) (xy -1.9 0.981128) (xy -1.65 0.731128) (xy -1.2 0.431128)
						(xy -0.4 0.131128) (xy -0.4 0.031128) (xy -2.9 0.021128) (xy -2.9 1.731128)
					)
					(width 0.2)
					(fill yes)
				)
				(gr_poly
					(pts
						(xy 2.4 1.71) (xy 2.117646 1.21) (xy 1.9 0.96) (xy 1.65 0.71) (xy 1.2 0.41) (xy 0.4 0.11) (xy 0.4 0.01)
						(xy 2.9 0) (xy 2.9 1.71)
					)
					(width 0.2)
					(fill yes)
				)
			)
		)
	)
)
